# S9S_MB_2U (Grand Teton) — schematic netlist excerpt (pin names and nets, part order shuffled) for the footprints in the layout excerpt that follows; sources: Cadence DE-HDL packaged netlist, KiCad conversion of 03242023_DA0F0TMBIJ0_F0T_Motherboard_J_brd_V01_OCP.brd

C878  Q_CAP_DIFFBUS  DIFF BUS_0.22UF 6.3V 20% X6S  pkg C0201  page 174 : \1\ = P5E_CPU0_PE3_TX_C_DN<11> ; \2\ = P5E_CPU0_PE3_TX_DN<11>
R371  Q_RES  1K 1% EMPTY  pkg 0402LF  page 198 : A = P3V3_AUX ; B = FM_PCH_BOOT_BIOS_STRAP
R1449  Q_RES  10K 1% CHIP  pkg 0402LF  page 204 : A = P3V3_AUX ; B = FM_BIOS_POST_CMPLT_N

(kicad_pcb
	(version 20260206)
	(generator "pcbnew")
	(generator_version "10.0")
	(general
		(thickness 1.6)
		(legacy_teardrops no)
	)
	(paper "A4")
	(title_block
		(title "03242023_DA0F0TMBIJ0_F0T_Motherboard_J_brd_V01_OCP.brd")
		(comment 1 "Grand Teton / footprints 307-309 of 6105")
	)
	(layers
		(0 "F.Cu" signal "TOP")
		(4 "In1.Cu" signal "GND")
		(6 "In2.Cu" signal "IN1")
		(8 "In3.Cu" signal "GND1")
		(10 "In4.Cu" signal "IN2")
		(12 "In5.Cu" signal "GND2")
		(14 "In6.Cu" signal "IN3")
		(16 "In7.Cu" signal "GND3")
		(18 "In8.Cu" signal "VCC")
		(20 "In9.Cu" signal "VCC1")
		(22 "In10.Cu" signal "GND4")
		(24 "In11.Cu" signal "IN4")
		(26 "In12.Cu" signal "GND5")
		(28 "In13.Cu" signal "IN5")
		(30 "In14.Cu" signal "GND6")
		(32 "In15.Cu" signal "IN6")
		(34 "In16.Cu" signal "GND7")
		(2 "B.Cu" signal "BOTTOM")
		(9 "F.Adhes" user "F.Adhesive")
		(11 "B.Adhes" user "B.Adhesive")
		(13 "F.Paste" user "Package Geometry/Pastemask Top")
		(15 "B.Paste" user "Package Geometry/Pastemask Bottom")
		(5 "F.SilkS" user "Ref Des/Silkscreen Top")
		(7 "B.SilkS" user "Ref Des/Silkscreen Bottom")
		(1 "F.Mask" user "Board Geometry/Soldermask Top")
		(3 "B.Mask" user "Board Geometry/Soldermask Bottom")
		(17 "Dwgs.User" user "User.Drawings")
		(19 "Cmts.User" user "User.Comments")
		(21 "Eco1.User" user "User.Eco1")
		(23 "Eco2.User" user "User.Eco2")
		(25 "Edge.Cuts" user "Board Geometry/Outline")
		(27 "Margin" user)
		(31 "F.CrtYd" user "Package Geometry/Place Bound Top")
		(29 "B.CrtYd" user "Package Geometry/Place Bound Bottom")
		(35 "F.Fab" user "Ref Des/Assembly Top")
		(33 "B.Fab" user "Ref Des/Assembly Bottom")
	)
	(footprint ""
		(layer "F.Cu")
		(at 317.396622 -53.787548)
		(property "Reference" "R371"
			(at 0 0 0)
			(layer "F.SilkS")
			(hide yes)
			(effects
				(font
					(size 1.27 1.27)
				)
			)
		)
		(property "Value" ""
			(at 0 0 0)
			(layer "F.Fab")
			(effects
				(font
					(size 1.27 1.27)
				)
			)
		)
		(duplicate_pad_numbers_are_jumpers no)
		(fp_line
			(start -0.7874 -0.4064)
			(end 0.7874 -0.4064)
			(stroke
				(width 0.1524)
				(type default)
			)
			(layer "F.SilkS")
		)
		(fp_line
			(start -0.7874 0.4064)
			(end -0.7874 -0.4064)
			(stroke
				(width 0.1524)
				(type default)
			)
			(layer "F.SilkS")
		)
		(fp_line
			(start 0.7874 -0.4064)
			(end 0.7874 0.4064)
			(stroke
				(width 0.1524)
				(type default)
			)
			(layer "F.SilkS")
		)
		(fp_line
			(start 0.7874 0.4064)
			(end -0.7874 0.4064)
			(stroke
				(width 0.1524)
				(type default)
			)
			(layer "F.SilkS")
		)
		(fp_line
			(start -0.67945 -0.305054)
			(end -0.12065 -0.305054)
			(stroke
				(width 0.1)
				(type default)
			)
			(layer "F.Fab")
		)
		(fp_line
			(start -0.67945 0.3048)
			(end -0.67945 -0.305054)
			(stroke
				(width 0.1)
				(type default)
			)
			(layer "F.Fab")
		)
		(fp_line
			(start -0.12065 -0.305054)
			(end -0.12065 -0.2794)
			(stroke
				(width 0.1)
				(type default)
			)
			(layer "F.Fab")
		)
		(fp_line
			(start -0.12065 -0.2794)
			(end 0.12065 -0.2794)
			(stroke
				(width 0.1)
				(type default)
			)
			(layer "F.Fab")
		)
		(fp_line
			(start -0.12065 0.2794)
			(end -0.12065 0.3048)
			(stroke
				(width 0.1)
				(type default)
			)
			(layer "F.Fab")
		)
		(fp_line
			(start -0.12065 0.3048)
			(end -0.67945 0.3048)
			(stroke
				(width 0.1)
				(type default)
			)
			(layer "F.Fab")
		)
		(fp_line
			(start 0.120396 0.2794)
			(end -0.12065 0.2794)
			(stroke
				(width 0.1)
				(type default)
			)
			(layer "F.Fab")
		)
		(fp_line
			(start 0.120396 0.3048)
			(end 0.120396 0.2794)
			(stroke
				(width 0.1)
				(type default)
			)
			(layer "F.Fab")
		)
		(fp_line
			(start 0.12065 -0.3048)
			(end 0.67945 -0.3048)
			(stroke
				(width 0.1)
				(type default)
			)
			(layer "F.Fab")
		)
		(fp_line
			(start 0.12065 -0.2794)
			(end 0.12065 -0.3048)
			(stroke
				(width 0.1)
				(type default)
			)
			(layer "F.Fab")
		)
		(fp_line
			(start 0.67945 -0.3048)
			(end 0.67945 0.3048)
			(stroke
				(width 0.1)
				(type default)
			)
			(layer "F.Fab")
		)
		(fp_line
			(start 0.67945 0.3048)
			(end 0.120396 0.3048)
			(stroke
				(width 0.1)
				(type default)
			)
			(layer "F.Fab")
		)
		(pad "1" smd circle
			(at -0.40005 0)
			(size 0 0)
			(layers "F.Cu" "F.Mask" "F.Paste")
			(net "P3V3_AUX")
		)
		(pad "2" smd circle
			(at 0.40005 0)
			(size 0 0)
			(layers "F.Cu" "F.Mask" "F.Paste")
			(net "FM_PCH_BOOT_BIOS_STRAP")
		)
	)
	(footprint ""
		(layer "F.Cu")
		(at 309.522622 -41.900348 180)
		(property "Reference" "R1449"
			(at 0 0 180)
			(layer "F.SilkS")
			(hide yes)
			(effects
				(font
					(size 1.27 1.27)
				)
			)
		)
		(property "Value" ""
			(at 0 0 180)
			(layer "F.Fab")
			(effects
				(font
					(size 1.27 1.27)
				)
			)
		)
		(duplicate_pad_numbers_are_jumpers no)
		(fp_line
			(start 0.7874 0.4064)
			(end -0.7874 0.4064)
			(stroke
				(width 0.1524)
				(type default)
			)
			(layer "F.SilkS")
		)
		(fp_line
			(start 0.7874 -0.4064)
			(end 0.7874 0.4064)
			(stroke
				(width 0.1524)
				(type default)
			)
			(layer "F.SilkS")
		)
		(fp_line
			(start -0.7874 0.4064)
			(end -0.7874 -0.4064)
			(stroke
				(width 0.1524)
				(type default)
			)
			(layer "F.SilkS")
		)
		(fp_line
			(start -0.7874 -0.4064)
			(end 0.7874 -0.4064)
			(stroke
				(width 0.1524)
				(type default)
			)
			(layer "F.SilkS")
		)
		(fp_line
			(start 0.67945 0.3048)
			(end 0.120396 0.3048)
			(stroke
				(width 0.1)
				(type default)
			)
			(layer "F.Fab")
		)
		(fp_line
			(start 0.67945 -0.3048)
			(end 0.67945 0.3048)
			(stroke
				(width 0.1)
				(type default)
			)
			(layer "F.Fab")
		)
		(fp_line
			(start 0.12065 -0.2794)
			(end 0.12065 -0.3048)
			(stroke
				(width 0.1)
				(type default)
			)
			(layer "F.Fab")
		)
		(fp_line
			(start 0.12065 -0.3048)
			(end 0.67945 -0.3048)
			(stroke
				(width 0.1)
				(type default)
			)
			(layer "F.Fab")
		)
		(fp_line
			(start 0.120396 0.3048)
			(end 0.120396 0.2794)
			(stroke
				(width 0.1)
				(type default)
			)
			(layer "F.Fab")
		)
		(fp_line
			(start 0.120396 0.2794)
			(end -0.12065 0.2794)
			(stroke
				(width 0.1)
				(type default)
			)
			(layer "F.Fab")
		)
		(fp_line
			(start -0.12065 0.3048)
			(end -0.67945 0.3048)
			(stroke
				(width 0.1)
				(type default)
			)
			(layer "F.Fab")
		)
		(fp_line
			(start -0.12065 0.2794)
			(end -0.12065 0.3048)
			(stroke
				(width 0.1)
				(type default)
			)
			(layer "F.Fab")
		)
		(fp_line
			(start -0.12065 -0.2794)
			(end 0.12065 -0.2794)
			(stroke
				(width 0.1)
				(type default)
			)
			(layer "F.Fab")
		)
		(fp_line
			(start -0.12065 -0.305054)
			(end -0.12065 -0.2794)
			(stroke
				(width 0.1)
				(type default)
			)
			(layer "F.Fab")
		)
		(fp_line
			(start -0.67945 0.3048)
			(end -0.67945 -0.305054)
			(stroke
				(width 0.1)
				(type default)
			)
			(layer "F.Fab")
		)
		(fp_line
			(start -0.67945 -0.305054)
			(end -0.12065 -0.305054)
			(stroke
				(width 0.1)
				(type default)
			)
			(layer "F.Fab")
		)
		(pad "1" smd circle
			(at -0.40005 0 180)
			(size 0 0)
			(layers "F.Cu" "F.Mask" "F.Paste")
			(net "P3V3_AUX")
		)
		(pad "2" smd circle
			(at 0.40005 0 180)
			(size 0 0)
			(layers "F.Cu" "F.Mask" "F.Paste")
			(net "FM_BIOS_POST_CMPLT_N")
		)
	)
	(footprint ""
		(layer "F.Cu")
		(at 384.99669 -408.517344 -90)
		(property "Reference" "C878"
			(at 0 0 270)
			(layer "F.SilkS")
			(hide yes)
			(effects
				(font
					(size 1.27 1.27)
				)
			)
		)
		(property "Value" ""
			(at 0 0 270)
			(layer "F.Fab")
			(effects
				(font
					(size 1.27 1.27)
				)
			)
		)
		(duplicate_pad_numbers_are_jumpers no)
		(fp_line
			(start -0.299974 0.150114)
			(end -0.299974 -0.150114)
			(stroke
				(width 0.1)
				(type default)
			)
			(layer "F.Fab")
		)
		(fp_line
			(start 0.299974 0.150114)
			(end -0.299974 0.150114)
			(stroke
				(width 0.1)
				(type default)
			)
			(layer "F.Fab")
		)
		(fp_line
			(start -0.299974 -0.150114)
			(end 0.299974 -0.150114)
			(stroke
				(width 0.1)
				(type default)
			)
			(layer "F.Fab")
		)
		(fp_line
			(start 0.299974 -0.150114)
			(end 0.299974 0.150114)
			(stroke
				(width 0.1)
				(type default)
			)
			(layer "F.Fab")
		)
		(pad "1" smd rect
			(at -0.2667 0 270)
			(size 0.3048 0.381)
			(layers "F.Cu" "F.Mask" "F.Paste")
			(net "P5E_CPU0_PE3_TX_C_DN<11>")
		)
		(pad "2" smd rect
			(at 0.2667 0 270)
			(size 0.3048 0.381)
			(layers "F.Cu" "F.Mask" "F.Paste")
			(net "P5E_CPU0_PE3_TX_DN<11>")
		)
	)
)
